(kicad_pcb
	(version 20241229)
	(generator "pcbnew")
	(generator_version "9.0")
	(general
		(thickness 1.552)
		(legacy_teardrops no)
	)
	(paper "A4")
	(title_block
		(date "2023-07-25")
		(rev "1.1.4")
		(comment 9 "footprints 124-127 of 379")
	)
	(layers
		(0 "F.Cu" signal)
		(4 "In1.Cu" signal)
		(6 "In2.Cu" signal)
		(8 "In3.Cu" signal)
		(10 "In4.Cu" signal)
		(12 "In5.Cu" signal)
		(14 "In6.Cu" signal)
		(2 "B.Cu" signal)
		(9 "F.Adhes" user "F.Adhesive")
		(11 "B.Adhes" user "B.Adhesive")
		(13 "F.Paste" user)
		(15 "B.Paste" user)
		(5 "F.SilkS" user "F.Silkscreen")
		(7 "B.SilkS" user "B.Silkscreen")
		(1 "F.Mask" user)
		(3 "B.Mask" user)
		(17 "Dwgs.User" user "User.Drawings")
		(19 "Cmts.User" user "User.Comments")
		(21 "Eco1.User" user "User.Eco1")
		(23 "Eco2.User" user "User.Eco2")
		(25 "Edge.Cuts" user)
		(27 "Margin" user)
		(31 "F.CrtYd" user "F.Courtyard")
		(29 "B.CrtYd" user "B.Courtyard")
		(35 "F.Fab" user)
		(33 "B.Fab" user)
	)
	(footprint "antmicro-footprints:C_0402_1005Metric"
		(layer "F.Cu")
		(at 129.48 63.26 -90)
		(descr "Capacitor SMD 0402")
		(tags "capacitor SMD 0402")
		(property "Reference" "C120"
			(at -1.385 -1.4 90)
			(layer "F.SilkS")
			(effects
				(font
					(size 0.65 0.65)
					(thickness 0.15)
				)
				(justify right bottom)
			)
		)
		(property "Value" "C_100n_0402"
			(at 0 1.4 90)
			(layer "F.Fab")
			(hide yes)
			(effects
				(font
					(size 0.7 0.7)
					(thickness 0.15)
				)
				(justify right bottom)
			)
		)
		(property "Datasheet" "https://www.murata.com/products/productdetail?partno=GRM155R61H104KE14%23"
			(at 0 0 270)
			(layer "F.Fab")
			(hide yes)
			(effects
				(font
					(size 1.27 1.27)
					(thickness 0.15)
				)
			)
		)
		(property "Description" "SMD Multilayer Ceramic Capacitor, 0.1 µF, 50 V, 0402 [1005 Metric], ± 10%, X5R, GRM Series"
			(at 0 0 270)
			(layer "F.Fab")
			(hide yes)
			(effects
				(font
					(size 1.27 1.27)
					(thickness 0.15)
				)
			)
		)
		(property "Author" "Antmicro"
			(at 66.22 192.74 0)
			(layer "F.Fab")
			(hide yes)
			(effects
				(font
					(size 1 1)
					(thickness 0.15)
				)
			)
		)
		(property "Dielectric" "X5R"
			(at 66.22 192.74 0)
			(layer "F.Fab")
			(hide yes)
			(effects
				(font
					(size 1 1)
					(thickness 0.15)
				)
			)
		)
		(property "License" "Apache-2.0"
			(at 66.22 192.74 0)
			(layer "F.Fab")
			(hide yes)
			(effects
				(font
					(size 1 1)
					(thickness 0.15)
				)
			)
		)
		(property "MPN" "GRM155R61H104KE14D"
			(at 66.22 192.74 0)
			(layer "F.Fab")
			(hide yes)
			(effects
				(font
					(size 1 1)
					(thickness 0.15)
				)
			)
		)
		(property "Manufacturer" "Murata"
			(at 66.22 192.74 0)
			(layer "F.Fab")
			(hide yes)
			(effects
				(font
					(size 1 1)
					(thickness 0.15)
				)
			)
		)
		(property "Val" "100n"
			(at 66.22 192.74 0)
			(layer "F.Fab")
			(hide yes)
			(effects
				(font
					(size 1 1)
					(thickness 0.15)
				)
			)
		)
		(property "Voltage" "50V"
			(at 66.22 192.74 0)
			(layer "F.Fab")
			(hide yes)
			(effects
				(font
					(size 1 1)
					(thickness 0.15)
				)
			)
		)
		(sheetname "/DDR3/")
		(sheetfile "ddr3.kicad_sch")
		(attr smd)
		(fp_rect
			(start -0.925 -0.47)
			(end 0.925 0.47)
			(stroke
				(width 0.05)
				(type default)
			)
			(fill no)
			(layer "F.CrtYd")
		)
		(fp_line
			(start -0.494 0.248)
			(end -0.494 -0.25)
			(stroke
				(width 0.15)
				(type solid)
			)
			(layer "F.Fab")
		)
		(fp_line
			(start 0.504 0.248)
			(end -0.494 0.248)
			(stroke
				(width 0.15)
				(type solid)
			)
			(layer "F.Fab")
		)
		(fp_line
			(start -0.494 -0.25)
			(end 0.504 -0.25)
			(stroke
				(width 0.15)
				(type solid)
			)
			(layer "F.Fab")
		)
		(fp_line
			(start 0.504 -0.25)
			(end 0.504 0.248)
			(stroke
				(width 0.15)
				(type solid)
			)
			(layer "F.Fab")
		)
		(fp_text user "Author: Antmicro"
			(at -0.939 3.399 270)
			(layer "F.Fab")
			(effects
				(font
					(size 0.7 0.7)
					(thickness 0.15)
				)
				(justify left bottom)
			)
		)
		(fp_text user "License: Apache-2.0"
			(at -0.939 5.799 270)
			(layer "F.Fab")
			(effects
				(font
					(size 0.7 0.7)
					(thickness 0.15)
				)
				(justify left bottom)
			)
		)
		(fp_text user "${REFERENCE}"
			(at -0.939 4.599 270)
			(layer "F.Fab")
			(effects
				(font
					(size 0.7 0.7)
					(thickness 0.15)
				)
				(justify left bottom)
			)
		)
		(pad "1" smd roundrect
			(at -0.48 0 270)
			(size 0.59 0.64)
			(layers "F.Cu" "F.Mask" "F.Paste")
			(roundrect_rratio 0.25)
			(net 1 "GND")
			(pintype "passive")
		)
		(pad "2" smd roundrect
			(at 0.48 0 270)
			(size 0.59 0.64)
			(layers "F.Cu" "F.Mask" "F.Paste")
			(roundrect_rratio 0.25)
			(net 5 "Vref")
			(pintype "passive")
		)
	)
	(footprint "antmicro-footprints:LED_0603_1608Metric_G"
		(layer "F.Cu")
		(at 162.83 119.15 90)
		(descr "LED SMD 0603 Green")
		(tags "LED SMD 0603 Green")
		(property "Reference" "D4"
			(at -0.09 0.8 90)
			(layer "F.SilkS")
			(effects
				(font
					(size 0.65 0.65)
					(thickness 0.15)
				)
				(justify left top)
			)
		)
		(property "Value" "LED_G_0603_LTST-C190GKT"
			(at 0 1.6 90)
			(layer "F.Fab")
			(hide yes)
			(effects
				(font
					(size 0.7 0.7)
					(thickness 0.15)
				)
				(justify left top)
			)
		)
		(property "Datasheet" "https://media.digikey.com/pdf/Data%20Sheets/Lite-On%20PDFs/LTST-C190GKT.pdf"
			(at 0 0 90)
			(layer "F.Fab")
			(hide yes)
			(effects
				(font
					(size 1.27 1.27)
					(thickness 0.15)
				)
			)
		)
		(property "Description" "LED, Green, SMD, 0603, 20 mA, 2.1 V, 569 nm"
			(at 0 0 90)
			(layer "F.Fab")
			(hide yes)
			(effects
				(font
					(size 1.27 1.27)
					(thickness 0.15)
				)
			)
		)
		(property "Author" "Antmicro"
			(at 43.68 281.98 0)
			(layer "F.Fab")
			(hide yes)
			(effects
				(font
					(size 1 1)
					(thickness 0.15)
				)
			)
		)
		(property "License" "Apache-2.0"
			(at 43.68 281.98 0)
			(layer "F.Fab")
			(hide yes)
			(effects
				(font
					(size 1 1)
					(thickness 0.15)
				)
			)
		)
		(property "MPN" "LTST-C190GKT"
			(at 43.68 281.98 0)
			(layer "F.Fab")
			(hide yes)
			(effects
				(font
					(size 1 1)
					(thickness 0.15)
				)
			)
		)
		(property "Manufacturer" "Lite-On"
			(at 43.68 281.98 0)
			(layer "F.Fab")
			(hide yes)
			(effects
				(font
					(size 1 1)
					(thickness 0.15)
				)
			)
		)
		(property "Color" "Green"
			(at 0 0 90)
			(unlocked yes)
			(layer "F.Fab")
			(hide yes)
			(effects
				(font
					(size 1 1)
					(thickness 0.15)
				)
			)
		)
		(sheetname "/Peripherals/")
		(sheetfile "peripherals.kicad_sch")
		(attr smd)
		(fp_line
			(start 0.22 -0.35)
			(end -0.22 -0.35)
			(stroke
				(width 0.15)
				(type solid)
			)
			(layer "F.SilkS")
		)
		(fp_line
			(start -1.18 -0.319)
			(end -1.18 0.321)
			(stroke
				(width 0.15)
				(type solid)
			)
			(layer "F.SilkS")
		)
		(fp_line
			(start 0.105328 0.001008)
			(end 0.24 0.001)
			(stroke
				(width 0.1)
				(type solid)
			)
			(layer "F.SilkS")
		)
		(fp_line
			(start -0.094672 0.001008)
			(end 0.105328 -0.198992)
			(stroke
				(width 0.1)
				(type solid)
			)
			(layer "F.SilkS")
		)
		(fp_line
			(start -0.094672 0.001008)
			(end -0.24 0.001008)
			(stroke
				(width 0.1)
				(type solid)
			)
			(layer "F.SilkS")
		)
		(fp_line
			(start 0.105328 0.201008)
			(end 0.105328 -0.198992)
			(stroke
				(width 0.1)
				(type solid)
			)
			(layer "F.SilkS")
		)
		(fp_line
			(start 0.105328 0.201008)
			(end -0.094672 0.001008)
			(stroke
				(width 0.1)
				(type solid)
			)
			(layer "F.SilkS")
		)
		(fp_line
			(start -0.094672 0.201008)
			(end -0.094672 -0.198992)
			(stroke
				(width 0.1)
				(type solid)
			)
			(layer "F.SilkS")
		)
		(fp_line
			(start 0.22 0.35)
			(end -0.22 0.35)
			(stroke
				(width 0.15)
				(type solid)
			)
			(layer "F.SilkS")
		)
		(fp_rect
			(start 1.25 0.65)
			(end -1.25 -0.65)
			(stroke
				(width 0.05)
				(type solid)
			)
			(fill no)
			(layer "F.CrtYd")
		)
		(fp_line
			(start 0.201 -0.202)
			(end -0.101 0)
			(stroke
				(width 0.15)
				(type solid)
			)
			(layer "F.Fab")
		)
		(fp_line
			(start -0.199 -0.202)
			(end -0.199 0.1)
			(stroke
				(width 0.15)
				(type solid)
			)
			(layer "F.Fab")
		)
		(fp_line
			(start 0.599 0)
			(end 0.201 0)
			(stroke
				(width 0.15)
				(type solid)
			)
			(layer "F.Fab")
		)
		(fp_line
			(start 0.201 0)
			(end 0.201 -0.202)
			(stroke
				(width 0.15)
				(type solid)
			)
			(layer "F.Fab")
		)
		(fp_line
			(start -0.101 0)
			(end 0.201 0.2)
			(stroke
				(width 0.15)
				(type solid)
			)
			(layer "F.Fab")
		)
		(fp_line
			(start -0.199 0)
			(end -0.597 0)
			(stroke
				(width 0.15)
				(type solid)
			)
			(layer "F.Fab")
		)
		(fp_line
			(start 0.201 0.2)
			(end 0.201 0)
			(stroke
				(width 0.15)
				(type solid)
			)
			(layer "F.Fab")
		)
		(fp_line
			(start -0.199 0.2)
			(end -0.199 0.1)
			(stroke
				(width 0.15)
				(type solid)
			)
			(layer "F.Fab")
		)
		(fp_rect
			(start 0.848 0.4)
			(end -0.85 -0.402)
			(stroke
				(width 0.15)
				(type solid)
			)
			(fill no)
			(layer "F.Fab")
		)
		(fp_text user "${REFERENCE}"
			(at -1.4224 5.999 90)
			(layer "F.Fab")
			(effects
				(font
					(size 0.7 0.7)
					(thickness 0.15)
				)
				(justify left bottom)
			)
		)
		(fp_text user "Author: Antmicro"
			(at -1.4224 4.799 90)
			(layer "F.Fab")
			(effects
				(font
					(size 0.7 0.7)
					(thickness 0.15)
				)
				(justify left bottom)
			)
		)
		(fp_text user "License: Apache-2.0"
			(at -1.4224 3.599 90)
			(layer "F.Fab")
			(effects
				(font
					(size 0.7 0.7)
					(thickness 0.15)
				)
				(justify left bottom)
			)
		)
		(pad "1" smd roundrect
			(at -0.7 0 270)
			(size 0.8 1)
			(layers "F.Cu" "F.Mask" "F.Paste")
			(roundrect_rratio 0.2)
			(net 1 "GND")
			(pinfunction "C")
			(pintype "passive")
		)
		(pad "2" smd roundrect
			(at 0.7 0 270)
			(size 0.8 1)
			(layers "F.Cu" "F.Mask" "F.Paste")
			(roundrect_rratio 0.2)
			(net 64 "Net-(D4-A)")
			(pinfunction "A")
			(pintype "passive")
		)
	)
	(footprint "antmicro-footprints:C_0603_1608Metric"
		(layer "F.Cu")
		(at 146.18 75.29 90)
		(descr "Capacitor SMD 0603")
		(tags "capacitor 0603")
		(property "Reference" "C26"
			(at -3.44 0.3 90)
			(layer "F.SilkS")
			(effects
				(font
					(size 0.65 0.65)
					(thickness 0.15)
				)
				(justify left bottom)
			)
		)
		(property "Value" "C_22u_0603"
			(at 0 1.6 90)
			(layer "F.Fab")
			(hide yes)
			(effects
				(font
					(size 0.7 0.7)
					(thickness 0.15)
				)
				(justify left bottom)
			)
		)
		(property "Datasheet" "https://www.murata.com/products/productdetail?partno=GRM188R60J226MEA0%23"
			(at 0 0 90)
			(layer "F.Fab")
			(hide yes)
			(effects
				(font
					(size 1.27 1.27)
					(thickness 0.15)
				)
			)
		)
		(property "Description" "SMD Multilayer Ceramic Capacitor, 22 µF, 6.3 V, 0603 [1608 Metric], ± 20%, X5R, GRM Series"
			(at 0 0 90)
			(layer "F.Fab")
			(hide yes)
			(effects
				(font
					(size 1.27 1.27)
					(thickness 0.15)
				)
			)
		)
		(property "Author" "Antmicro"
			(at 221.43 -71.03 0)
			(layer "F.Fab")
			(hide yes)
			(effects
				(font
					(size 1 1)
					(thickness 0.15)
				)
			)
		)
		(property "Dielectric" ""
			(at 221.43 -71.03 0)
			(layer "F.Fab")
			(hide yes)
			(effects
				(font
					(size 1 1)
					(thickness 0.15)
				)
			)
		)
		(property "License" "Apache-2.0"
			(at 221.43 -71.03 0)
			(layer "F.Fab")
			(hide yes)
			(effects
				(font
					(size 1 1)
					(thickness 0.15)
				)
			)
		)
		(property "MPN" "GRM188R60J226MEA0D"
			(at 221.43 -71.03 0)
			(layer "F.Fab")
			(hide yes)
			(effects
				(font
					(size 1 1)
					(thickness 0.15)
				)
			)
		)
		(property "Manufacturer" "Murata"
			(at 221.43 -71.03 0)
			(layer "F.Fab")
			(hide yes)
			(effects
				(font
					(size 1 1)
					(thickness 0.15)
				)
			)
		)
		(property "Val" "22u"
			(at 221.43 -71.03 0)
			(layer "F.Fab")
			(hide yes)
			(effects
				(font
					(size 1 1)
					(thickness 0.15)
				)
			)
		)
		(property "Voltage" ""
			(at 221.43 -71.03 0)
			(layer "F.Fab")
			(hide yes)
			(effects
				(font
					(size 1 1)
					(thickness 0.15)
				)
			)
		)
		(sheetname "/Power Supply/")
		(sheetfile "supply.kicad_sch")
		(attr smd)
		(fp_line
			(start -0.15 -0.4)
			(end 0.15 -0.4)
			(stroke
				(width 0.15)
				(type solid)
			)
			(layer "F.SilkS")
		)
		(fp_line
			(start -0.15 0.4)
			(end 0.15 0.4)
			(stroke
				(width 0.15)
				(type solid)
			)
			(layer "F.SilkS")
		)
		(fp_rect
			(start -1.25 -0.65)
			(end 1.25 0.65)
			(stroke
				(width 0.05)
				(type solid)
			)
			(fill no)
			(layer "F.CrtYd")
		)
		(fp_rect
			(start -0.8 -0.4)
			(end 0.8 0.4)
			(stroke
				(width 0.15)
				(type solid)
			)
			(fill no)
			(layer "F.Fab")
		)
		(fp_text user "Author: Antmicro"
			(at -1.682 4.894 90)
			(layer "F.Fab")
			(effects
				(font
					(size 0.7 0.7)
					(thickness 0.15)
				)
				(justify left bottom)
			)
		)
		(fp_text user "${REFERENCE}"
			(at -1.682 3.895 90)
			(layer "F.Fab")
			(effects
				(font
					(size 0.7 0.7)
					(thickness 0.15)
				)
				(justify left bottom)
			)
		)
		(fp_text user "License: Apache-2.0"
			(at -1.682 5.895 90)
			(layer "F.Fab")
			(effects
				(font
					(size 0.7 0.7)
					(thickness 0.15)
				)
				(justify left bottom)
			)
		)
		(pad "1" smd roundrect
			(at -0.7 0 90)
			(size 0.8 1)
			(layers "F.Cu" "F.Mask" "F.Paste")
			(roundrect_rratio 0.2)
			(net 1 "GND")
			(pintype "passive")
		)
		(pad "2" smd roundrect
			(at 0.7 0 90)
			(size 0.8 1)
			(layers "F.Cu" "F.Mask" "F.Paste")
			(roundrect_rratio 0.2)
			(net 273 "/Power Supply/1V0_OUT")
			(pintype "passive")
		)
	)
	(footprint "antmicro-footprints:R_0805_2012Metric"
		(layer "F.Cu")
		(at 141.13 62.64 180)
		(property "Reference" "R42"
			(at 3.9 -0.3 180)
			(layer "F.SilkS")
			(effects
				(font
					(size 0.65 0.65)
					(thickness 0.15)
				)
				(justify left bottom)
			)
		)
		(property "Value" "R_0R_0805"
			(at 0 1.8 180)
			(layer "F.Fab")
			(hide yes)
			(effects
				(font
					(size 0.7 0.7)
					(thickness 0.15)
				)
				(justify left bottom)
			)
		)
		(property "Datasheet" "https://www.vishay.com/docs/20035/dcrcwe3.pdf"
			(at 0 0 180)
			(layer "F.Fab")
			(hide yes)
			(effects
				(font
					(size 1.27 1.27)
					(thickness 0.15)
				)
			)
		)
		(property "Description" "Zero Ohm Resistor, Jumper, 0805 [2012 Metric], Thick Film, 125 mW, 2.5 A, Surface Mount Device"
			(at 0 0 180)
			(layer "F.Fab")
			(hide yes)
			(effects
				(font
					(size 1.27 1.27)
					(thickness 0.15)
				)
			)
		)
		(property "Author" "Antmicro"
			(at 282.26 125.28 0)
			(layer "F.Fab")
			(hide yes)
			(effects
				(font
					(size 1 1)
					(thickness 0.15)
				)
			)
		)
		(property "Current" "2.5A"
			(at 282.26 125.28 0)
			(layer "F.Fab")
			(hide yes)
			(effects
				(font
					(size 1 1)
					(thickness 0.15)
				)
			)
		)
		(property "License" "Apache-2.0"
			(at 282.26 125.28 0)
			(layer "F.Fab")
			(hide yes)
			(effects
				(font
					(size 1 1)
					(thickness 0.15)
				)
			)
		)
		(property "MPN" "CRCW08050000Z0EA"
			(at 282.26 125.28 0)
			(layer "F.Fab")
			(hide yes)
			(effects
				(font
					(size 1 1)
					(thickness 0.15)
				)
			)
		)
		(property "Manufacturer" "Vishay"
			(at 282.26 125.28 0)
			(layer "F.Fab")
			(hide yes)
			(effects
				(font
					(size 1 1)
					(thickness 0.15)
				)
			)
		)
		(property "Tolerance" "~"
			(at 282.26 125.28 0)
			(layer "F.Fab")
			(hide yes)
			(effects
				(font
					(size 1 1)
					(thickness 0.15)
				)
			)
		)
		(property "Val" "0R"
			(at 282.26 125.28 0)
			(layer "F.Fab")
			(hide yes)
			(effects
				(font
					(size 1 1)
					(thickness 0.15)
				)
			)
		)
		(sheetname "/Power Supply/")
		(sheetfile "supply.kicad_sch")
		(attr smd)
		(fp_line
			(start -0.3 -0.701)
			(end 0.298 -0.701)
			(stroke
				(width 0.15)
				(type solid)
			)
			(layer "F.SilkS")
		)
		(fp_line
			(start -0.32 0.699)
			(end 0.28 0.699)
			(stroke
				(width 0.15)
				(type solid)
			)
			(layer "F.SilkS")
		)
		(fp_rect
			(start 1.95 -0.9)
			(end -1.95 0.9)
			(stroke
				(width 0.05)
				(type default)
			)
			(fill no)
			(layer "F.CrtYd")
		)
		(fp_line
			(start 0.949 -0.677)
			(end 0.949 0.675)
			(stroke
				(width 0.15)
				(type solid)
			)
			(layer "F.Fab")
		)
		(fp_line
			(start -0.951 0.68)
			(end 0.949 0.68)
			(stroke
				(width 0.15)
				(type solid)
			)
			(layer "F.Fab")
		)
		(fp_line
			(start -0.951 -0.677)
			(end -0.951 0.675)
			(stroke
				(width 0.15)
				(type solid)
			)
			(layer "F.Fab")
		)
		(fp_line
			(start -0.951 -0.682)
			(end 0.949 -0.682)
			(stroke
				(width 0.15)
				(type solid)
			)
			(layer "F.Fab")
		)
		(fp_text user "${REFERENCE}"
			(at -1.9 3.1 180)
			(layer "F.Fab")
			(effects
				(font
					(size 0.7 0.7)
					(thickness 0.15)
				)
				(justify left bottom)
			)
		)
		(fp_text user "License: Apache-2.0"
			(at -1.9 5.75 180)
			(layer "F.Fab")
			(effects
				(font
					(size 0.7 0.7)
					(thickness 0.15)
				)
				(justify left bottom)
			)
		)
		(fp_text user "Author: Antmicro"
			(at -1.9 4.4 180)
			(layer "F.Fab")
			(effects
				(font
					(size 0.7 0.7)
					(thickness 0.15)
				)
				(justify left bottom)
			)
		)
		(pad "1" smd roundrect
			(at -1.1 0 180)
			(size 1.2 1.3)
			(layers "F.Cu" "F.Mask" "F.Paste")
			(roundrect_rratio 0.25)
			(net 274 "/Power Supply/1V5_OUT")
			(pintype "passive")
		)
		(pad "2" smd roundrect
			(at 1.1 0 180)
			(size 1.2 1.3)
			(layers "F.Cu" "F.Mask" "F.Paste")
			(roundrect_rratio 0.25)
			(net 248 "+1V5")
			(pintype "passive")
		)
	)
)
